(kicad_pcb
	(version 20260206)
	(generator "pcbnew")
	(generator_version "10.0")
	(general
		(thickness 1.6)
		(legacy_teardrops no)
	)
	(paper "A4")
	(title_block
		(title "04192023_DAF0TMB3IC0_F0TG_MB_C_brd_V02_OCP.brd")
		(comment 1 "Grand Teton / footprints 3373-3378 of 8354")
	)
	(layers
		(0 "F.Cu" signal "TOP")
		(4 "In1.Cu" signal "GND")
		(6 "In2.Cu" signal "IN1")
		(8 "In3.Cu" signal "GND1")
		(10 "In4.Cu" signal "IN2")
		(12 "In5.Cu" signal "GND2")
		(14 "In6.Cu" signal "IN3")
		(16 "In7.Cu" signal "GND3")
		(18 "In8.Cu" signal "VCC")
		(20 "In9.Cu" signal "VCC1")
		(22 "In10.Cu" signal "GND4")
		(24 "In11.Cu" signal "IN4")
		(26 "In12.Cu" signal "GND5")
		(28 "In13.Cu" signal "IN5")
		(30 "In14.Cu" signal "GND6")
		(32 "In15.Cu" signal "IN6")
		(34 "In16.Cu" signal "GND7")
		(2 "B.Cu" signal "BOTTOM")
		(9 "F.Adhes" user "F.Adhesive")
		(11 "B.Adhes" user "B.Adhesive")
		(13 "F.Paste" user "Package Geometry/Pastemask Top")
		(15 "B.Paste" user "Package Geometry/Pastemask Bottom")
		(5 "F.SilkS" user "Ref Des/Silkscreen Top")
		(7 "B.SilkS" user "Ref Des/Silkscreen Bottom")
		(1 "F.Mask" user "Board Geometry/Soldermask Top")
		(3 "B.Mask" user "Board Geometry/Soldermask Bottom")
		(17 "Dwgs.User" user "User.Drawings")
		(19 "Cmts.User" user "User.Comments")
		(21 "Eco1.User" user "User.Eco1")
		(23 "Eco2.User" user "User.Eco2")
		(25 "Edge.Cuts" user "Board Geometry/Outline")
		(27 "Margin" user)
		(31 "F.CrtYd" user "Package Geometry/Place Bound Top")
		(29 "B.CrtYd" user "Package Geometry/Place Bound Bottom")
		(35 "F.Fab" user "Ref Des/Assembly Top")
		(33 "B.Fab" user "Ref Des/Assembly Bottom")
	)
	(footprint ""
		(layer "F.Cu")
		(at 97.745296 -422.43248 90)
		(property "Reference" "C32"
			(at 0 0 90)
			(layer "F.SilkS")
			(hide yes)
			(effects
				(font
					(size 1.27 1.27)
				)
			)
		)
		(property "Value" ""
			(at 0 0 90)
			(layer "F.Fab")
			(effects
				(font
					(size 1.27 1.27)
				)
			)
		)
		(duplicate_pad_numbers_are_jumpers no)
		(fp_line
			(start 0.7874 -0.4064)
			(end 0.7874 0.4064)
			(stroke
				(width 0.1524)
				(type default)
			)
			(layer "F.SilkS")
		)
		(fp_line
			(start -0.7874 -0.4064)
			(end 0.7874 -0.4064)
			(stroke
				(width 0.1524)
				(type default)
			)
			(layer "F.SilkS")
		)
		(fp_line
			(start 0.7874 0.4064)
			(end -0.7874 0.4064)
			(stroke
				(width 0.1524)
				(type default)
			)
			(layer "F.SilkS")
		)
		(fp_line
			(start -0.7874 0.4064)
			(end -0.7874 -0.4064)
			(stroke
				(width 0.1524)
				(type default)
			)
			(layer "F.SilkS")
		)
		(fp_line
			(start -0.12065 -0.305054)
			(end -0.12065 -0.2794)
			(stroke
				(width 0.1)
				(type default)
			)
			(layer "F.Fab")
		)
		(fp_line
			(start -0.67945 -0.305054)
			(end -0.12065 -0.305054)
			(stroke
				(width 0.1)
				(type default)
			)
			(layer "F.Fab")
		)
		(fp_line
			(start 0.67945 -0.3048)
			(end 0.67945 0.3048)
			(stroke
				(width 0.1)
				(type default)
			)
			(layer "F.Fab")
		)
		(fp_line
			(start 0.12065 -0.3048)
			(end 0.67945 -0.3048)
			(stroke
				(width 0.1)
				(type default)
			)
			(layer "F.Fab")
		)
		(fp_line
			(start 0.12065 -0.2794)
			(end 0.12065 -0.3048)
			(stroke
				(width 0.1)
				(type default)
			)
			(layer "F.Fab")
		)
		(fp_line
			(start -0.12065 -0.2794)
			(end 0.12065 -0.2794)
			(stroke
				(width 0.1)
				(type default)
			)
			(layer "F.Fab")
		)
		(fp_line
			(start 0.120396 0.2794)
			(end -0.12065 0.2794)
			(stroke
				(width 0.1)
				(type default)
			)
			(layer "F.Fab")
		)
		(fp_line
			(start -0.12065 0.2794)
			(end -0.12065 0.3048)
			(stroke
				(width 0.1)
				(type default)
			)
			(layer "F.Fab")
		)
		(fp_line
			(start 0.67945 0.3048)
			(end 0.120396 0.3048)
			(stroke
				(width 0.1)
				(type default)
			)
			(layer "F.Fab")
		)
		(fp_line
			(start 0.120396 0.3048)
			(end 0.120396 0.2794)
			(stroke
				(width 0.1)
				(type default)
			)
			(layer "F.Fab")
		)
		(fp_line
			(start -0.12065 0.3048)
			(end -0.67945 0.3048)
			(stroke
				(width 0.1)
				(type default)
			)
			(layer "F.Fab")
		)
		(fp_line
			(start -0.67945 0.3048)
			(end -0.67945 -0.305054)
			(stroke
				(width 0.1)
				(type default)
			)
			(layer "F.Fab")
		)
		(pad "1" smd circle
			(at -0.40005 0 90)
			(size 0 0)
			(layers "F.Cu" "F.Mask" "F.Paste")
			(net "P3V3_AUX")
		)
		(pad "2" smd circle
			(at 0.40005 0 90)
			(size 0 0)
			(layers "F.Cu" "F.Mask" "F.Paste")
			(net "GND")
		)
	)
	(footprint ""
		(layer "F.Cu")
		(at 148.499068 -109.721904 180)
		(property "Reference" "R1654"
			(at 0 0 180)
			(layer "F.SilkS")
			(hide yes)
			(effects
				(font
					(size 1.27 1.27)
				)
			)
		)
		(property "Value" ""
			(at 0 0 180)
			(layer "F.Fab")
			(effects
				(font
					(size 1.27 1.27)
				)
			)
		)
		(duplicate_pad_numbers_are_jumpers no)
		(fp_line
			(start 0.7874 0.4064)
			(end -0.7874 0.4064)
			(stroke
				(width 0.1524)
				(type default)
			)
			(layer "F.SilkS")
		)
		(fp_line
			(start 0.7874 -0.4064)
			(end 0.7874 0.4064)
			(stroke
				(width 0.1524)
				(type default)
			)
			(layer "F.SilkS")
		)
		(fp_line
			(start -0.7874 0.4064)
			(end -0.7874 -0.4064)
			(stroke
				(width 0.1524)
				(type default)
			)
			(layer "F.SilkS")
		)
		(fp_line
			(start -0.7874 -0.4064)
			(end 0.7874 -0.4064)
			(stroke
				(width 0.1524)
				(type default)
			)
			(layer "F.SilkS")
		)
		(fp_line
			(start 0.67945 0.3048)
			(end 0.120396 0.3048)
			(stroke
				(width 0.1)
				(type default)
			)
			(layer "F.Fab")
		)
		(fp_line
			(start 0.67945 -0.3048)
			(end 0.67945 0.3048)
			(stroke
				(width 0.1)
				(type default)
			)
			(layer "F.Fab")
		)
		(fp_line
			(start 0.12065 -0.2794)
			(end 0.12065 -0.3048)
			(stroke
				(width 0.1)
				(type default)
			)
			(layer "F.Fab")
		)
		(fp_line
			(start 0.12065 -0.3048)
			(end 0.67945 -0.3048)
			(stroke
				(width 0.1)
				(type default)
			)
			(layer "F.Fab")
		)
		(fp_line
			(start 0.120396 0.3048)
			(end 0.120396 0.2794)
			(stroke
				(width 0.1)
				(type default)
			)
			(layer "F.Fab")
		)
		(fp_line
			(start 0.120396 0.2794)
			(end -0.12065 0.2794)
			(stroke
				(width 0.1)
				(type default)
			)
			(layer "F.Fab")
		)
		(fp_line
			(start -0.12065 0.3048)
			(end -0.67945 0.3048)
			(stroke
				(width 0.1)
				(type default)
			)
			(layer "F.Fab")
		)
		(fp_line
			(start -0.12065 0.2794)
			(end -0.12065 0.3048)
			(stroke
				(width 0.1)
				(type default)
			)
			(layer "F.Fab")
		)
		(fp_line
			(start -0.12065 -0.2794)
			(end 0.12065 -0.2794)
			(stroke
				(width 0.1)
				(type default)
			)
			(layer "F.Fab")
		)
		(fp_line
			(start -0.12065 -0.305054)
			(end -0.12065 -0.2794)
			(stroke
				(width 0.1)
				(type default)
			)
			(layer "F.Fab")
		)
		(fp_line
			(start -0.67945 0.3048)
			(end -0.67945 -0.305054)
			(stroke
				(width 0.1)
				(type default)
			)
			(layer "F.Fab")
		)
		(fp_line
			(start -0.67945 -0.305054)
			(end -0.12065 -0.305054)
			(stroke
				(width 0.1)
				(type default)
			)
			(layer "F.Fab")
		)
		(pad "1" smd circle
			(at -0.40005 0 180)
			(size 0 0)
			(layers "F.Cu" "F.Mask" "F.Paste")
			(net "VR_P5V_EN_D_R")
		)
		(pad "2" smd circle
			(at 0.40005 0 180)
			(size 0 0)
			(layers "F.Cu" "F.Mask" "F.Paste")
			(net "VR_P5V_EN_D_R1")
		)
	)
	(footprint ""
		(layer "F.Cu")
		(at 174.57674 -129.377948 90)
		(property "Reference" "R4145"
			(at 0 0 90)
			(layer "F.SilkS")
			(hide yes)
			(effects
				(font
					(size 1.27 1.27)
				)
			)
		)
		(property "Value" ""
			(at 0 0 90)
			(layer "F.Fab")
			(effects
				(font
					(size 1.27 1.27)
				)
			)
		)
		(duplicate_pad_numbers_are_jumpers no)
		(fp_line
			(start 0.7874 -0.4064)
			(end 0.7874 0.4064)
			(stroke
				(width 0.1524)
				(type default)
			)
			(layer "F.SilkS")
		)
		(fp_line
			(start -0.7874 -0.4064)
			(end 0.7874 -0.4064)
			(stroke
				(width 0.1524)
				(type default)
			)
			(layer "F.SilkS")
		)
		(fp_line
			(start 0.7874 0.4064)
			(end -0.7874 0.4064)
			(stroke
				(width 0.1524)
				(type default)
			)
			(layer "F.SilkS")
		)
		(fp_line
			(start -0.7874 0.4064)
			(end -0.7874 -0.4064)
			(stroke
				(width 0.1524)
				(type default)
			)
			(layer "F.SilkS")
		)
		(fp_line
			(start -0.12065 -0.305054)
			(end -0.12065 -0.2794)
			(stroke
				(width 0.1)
				(type default)
			)
			(layer "F.Fab")
		)
		(fp_line
			(start -0.67945 -0.305054)
			(end -0.12065 -0.305054)
			(stroke
				(width 0.1)
				(type default)
			)
			(layer "F.Fab")
		)
		(fp_line
			(start 0.67945 -0.3048)
			(end 0.67945 0.3048)
			(stroke
				(width 0.1)
				(type default)
			)
			(layer "F.Fab")
		)
		(fp_line
			(start 0.12065 -0.3048)
			(end 0.67945 -0.3048)
			(stroke
				(width 0.1)
				(type default)
			)
			(layer "F.Fab")
		)
		(fp_line
			(start 0.12065 -0.2794)
			(end 0.12065 -0.3048)
			(stroke
				(width 0.1)
				(type default)
			)
			(layer "F.Fab")
		)
		(fp_line
			(start -0.12065 -0.2794)
			(end 0.12065 -0.2794)
			(stroke
				(width 0.1)
				(type default)
			)
			(layer "F.Fab")
		)
		(fp_line
			(start 0.120396 0.2794)
			(end -0.12065 0.2794)
			(stroke
				(width 0.1)
				(type default)
			)
			(layer "F.Fab")
		)
		(fp_line
			(start -0.12065 0.2794)
			(end -0.12065 0.3048)
			(stroke
				(width 0.1)
				(type default)
			)
			(layer "F.Fab")
		)
		(fp_line
			(start 0.67945 0.3048)
			(end 0.120396 0.3048)
			(stroke
				(width 0.1)
				(type default)
			)
			(layer "F.Fab")
		)
		(fp_line
			(start 0.120396 0.3048)
			(end 0.120396 0.2794)
			(stroke
				(width 0.1)
				(type default)
			)
			(layer "F.Fab")
		)
		(fp_line
			(start -0.12065 0.3048)
			(end -0.67945 0.3048)
			(stroke
				(width 0.1)
				(type default)
			)
			(layer "F.Fab")
		)
		(fp_line
			(start -0.67945 0.3048)
			(end -0.67945 -0.305054)
			(stroke
				(width 0.1)
				(type default)
			)
			(layer "F.Fab")
		)
		(pad "1" smd circle
			(at -0.40005 0 90)
			(size 0 0)
			(layers "F.Cu" "F.Mask" "F.Paste")
			(net "PRSNT_CABLE_GPU_B3_ISO_R_N")
		)
		(pad "2" smd circle
			(at 0.40005 0 90)
			(size 0 0)
			(layers "F.Cu" "F.Mask" "F.Paste")
			(net "PRSNT_CABLE_GPU_B3_ISO_N")
		)
	)
	(footprint ""
		(layer "F.Cu")
		(at 173.171358 -387.737604)
		(property "Reference" "C370"
			(at 0 0 0)
			(layer "F.SilkS")
			(hide yes)
			(effects
				(font
					(size 1.27 1.27)
				)
			)
		)
		(property "Value" ""
			(at 0 0 0)
			(layer "F.Fab")
			(effects
				(font
					(size 1.27 1.27)
				)
			)
		)
		(duplicate_pad_numbers_are_jumpers no)
		(fp_line
			(start -0.7874 -0.4064)
			(end 0.7874 -0.4064)
			(stroke
				(width 0.1524)
				(type default)
			)
			(layer "F.SilkS")
		)
		(fp_line
			(start -0.7874 0.4064)
			(end -0.7874 -0.4064)
			(stroke
				(width 0.1524)
				(type default)
			)
			(layer "F.SilkS")
		)
		(fp_line
			(start 0.7874 -0.4064)
			(end 0.7874 0.4064)
			(stroke
				(width 0.1524)
				(type default)
			)
			(layer "F.SilkS")
		)
		(fp_line
			(start 0.7874 0.4064)
			(end -0.7874 0.4064)
			(stroke
				(width 0.1524)
				(type default)
			)
			(layer "F.SilkS")
		)
		(fp_line
			(start -0.67945 -0.305054)
			(end -0.12065 -0.305054)
			(stroke
				(width 0.1)
				(type default)
			)
			(layer "F.Fab")
		)
		(fp_line
			(start -0.67945 0.3048)
			(end -0.67945 -0.305054)
			(stroke
				(width 0.1)
				(type default)
			)
			(layer "F.Fab")
		)
		(fp_line
			(start -0.12065 -0.305054)
			(end -0.12065 -0.2794)
			(stroke
				(width 0.1)
				(type default)
			)
			(layer "F.Fab")
		)
		(fp_line
			(start -0.12065 -0.2794)
			(end 0.12065 -0.2794)
			(stroke
				(width 0.1)
				(type default)
			)
			(layer "F.Fab")
		)
		(fp_line
			(start -0.12065 0.2794)
			(end -0.12065 0.3048)
			(stroke
				(width 0.1)
				(type default)
			)
			(layer "F.Fab")
		)
		(fp_line
			(start -0.12065 0.3048)
			(end -0.67945 0.3048)
			(stroke
				(width 0.1)
				(type default)
			)
			(layer "F.Fab")
		)
		(fp_line
			(start 0.120396 0.2794)
			(end -0.12065 0.2794)
			(stroke
				(width 0.1)
				(type default)
			)
			(layer "F.Fab")
		)
		(fp_line
			(start 0.120396 0.3048)
			(end 0.120396 0.2794)
			(stroke
				(width 0.1)
				(type default)
			)
			(layer "F.Fab")
		)
		(fp_line
			(start 0.12065 -0.3048)
			(end 0.67945 -0.3048)
			(stroke
				(width 0.1)
				(type default)
			)
			(layer "F.Fab")
		)
		(fp_line
			(start 0.12065 -0.2794)
			(end 0.12065 -0.3048)
			(stroke
				(width 0.1)
				(type default)
			)
			(layer "F.Fab")
		)
		(fp_line
			(start 0.67945 -0.3048)
			(end 0.67945 0.3048)
			(stroke
				(width 0.1)
				(type default)
			)
			(layer "F.Fab")
		)
		(fp_line
			(start 0.67945 0.3048)
			(end 0.120396 0.3048)
			(stroke
				(width 0.1)
				(type default)
			)
			(layer "F.Fab")
		)
		(pad "1" smd circle
			(at -0.40005 0)
			(size 0 0)
			(layers "F.Cu" "F.Mask" "F.Paste")
			(net "P1V8_CPU1_RT_1D")
		)
		(pad "2" smd circle
			(at 0.40005 0)
			(size 0 0)
			(layers "F.Cu" "F.Mask" "F.Paste")
			(net "GND")
		)
	)
	(footprint ""
		(layer "F.Cu")
		(at 192.786 -92.801948 -90)
		(property "Reference" "R6052"
			(at 0 0 270)
			(layer "F.SilkS")
			(hide yes)
			(effects
				(font
					(size 1.27 1.27)
				)
			)
		)
		(property "Value" ""
			(at 0 0 270)
			(layer "F.Fab")
			(effects
				(font
					(size 1.27 1.27)
				)
			)
		)
		(duplicate_pad_numbers_are_jumpers no)
		(fp_line
			(start -0.7874 0.4064)
			(end -0.7874 -0.4064)
			(stroke
				(width 0.1524)
				(type default)
			)
			(layer "F.SilkS")
		)
		(fp_line
			(start 0.7874 0.4064)
			(end -0.7874 0.4064)
			(stroke
				(width 0.1524)
				(type default)
			)
			(layer "F.SilkS")
		)
		(fp_line
			(start -0.7874 -0.4064)
			(end 0.7874 -0.4064)
			(stroke
				(width 0.1524)
				(type default)
			)
			(layer "F.SilkS")
		)
		(fp_line
			(start 0.7874 -0.4064)
			(end 0.7874 0.4064)
			(stroke
				(width 0.1524)
				(type default)
			)
			(layer "F.SilkS")
		)
		(fp_line
			(start -0.67945 0.3048)
			(end -0.67945 -0.305054)
			(stroke
				(width 0.1)
				(type default)
			)
			(layer "F.Fab")
		)
		(fp_line
			(start -0.12065 0.3048)
			(end -0.67945 0.3048)
			(stroke
				(width 0.1)
				(type default)
			)
			(layer "F.Fab")
		)
		(fp_line
			(start 0.120396 0.3048)
			(end 0.120396 0.2794)
			(stroke
				(width 0.1)
				(type default)
			)
			(layer "F.Fab")
		)
		(fp_line
			(start 0.67945 0.3048)
			(end 0.120396 0.3048)
			(stroke
				(width 0.1)
				(type default)
			)
			(layer "F.Fab")
		)
		(fp_line
			(start -0.12065 0.2794)
			(end -0.12065 0.3048)
			(stroke
				(width 0.1)
				(type default)
			)
			(layer "F.Fab")
		)
		(fp_line
			(start 0.120396 0.2794)
			(end -0.12065 0.2794)
			(stroke
				(width 0.1)
				(type default)
			)
			(layer "F.Fab")
		)
		(fp_line
			(start -0.12065 -0.2794)
			(end 0.12065 -0.2794)
			(stroke
				(width 0.1)
				(type default)
			)
			(layer "F.Fab")
		)
		(fp_line
			(start 0.12065 -0.2794)
			(end 0.12065 -0.3048)
			(stroke
				(width 0.1)
				(type default)
			)
			(layer "F.Fab")
		)
		(fp_line
			(start 0.12065 -0.3048)
			(end 0.67945 -0.3048)
			(stroke
				(width 0.1)
				(type default)
			)
			(layer "F.Fab")
		)
		(fp_line
			(start 0.67945 -0.3048)
			(end 0.67945 0.3048)
			(stroke
				(width 0.1)
				(type default)
			)
			(layer "F.Fab")
		)
		(fp_line
			(start -0.67945 -0.305054)
			(end -0.12065 -0.305054)
			(stroke
				(width 0.1)
				(type default)
			)
			(layer "F.Fab")
		)
		(fp_line
			(start -0.12065 -0.305054)
			(end -0.12065 -0.2794)
			(stroke
				(width 0.1)
				(type default)
			)
			(layer "F.Fab")
		)
		(pad "1" smd circle
			(at -0.40005 0 270)
			(size 0 0)
			(layers "F.Cu" "F.Mask" "F.Paste")
			(net "E1S_0_PRSNT_R_N")
		)
		(pad "2" smd circle
			(at 0.40005 0 270)
			(size 0 0)
			(layers "F.Cu" "F.Mask" "F.Paste")
			(net "E1S_0_PRSNT_N")
		)
	)
	(footprint ""
		(layer "F.Cu")
		(at 105.537 -418.973 180)
		(property "Reference" "R3397"
			(at 0 0 180)
			(layer "F.SilkS")
			(hide yes)
			(effects
				(font
					(size 1.27 1.27)
				)
			)
		)
		(property "Value" ""
			(at 0 0 180)
			(layer "F.Fab")
			(effects
				(font
					(size 1.27 1.27)
				)
			)
		)
		(duplicate_pad_numbers_are_jumpers no)
		(fp_line
			(start 0.7874 0.4064)
			(end -0.7874 0.4064)
			(stroke
				(width 0.1524)
				(type default)
			)
			(layer "F.SilkS")
		)
		(fp_line
			(start 0.7874 -0.4064)
			(end 0.7874 0.4064)
			(stroke
				(width 0.1524)
				(type default)
			)
			(layer "F.SilkS")
		)
		(fp_line
			(start -0.7874 0.4064)
			(end -0.7874 -0.4064)
			(stroke
				(width 0.1524)
				(type default)
			)
			(layer "F.SilkS")
		)
		(fp_line
			(start -0.7874 -0.4064)
			(end 0.7874 -0.4064)
			(stroke
				(width 0.1524)
				(type default)
			)
			(layer "F.SilkS")
		)
		(fp_line
			(start 0.67945 0.3048)
			(end 0.120396 0.3048)
			(stroke
				(width 0.1)
				(type default)
			)
			(layer "F.Fab")
		)
		(fp_line
			(start 0.67945 -0.3048)
			(end 0.67945 0.3048)
			(stroke
				(width 0.1)
				(type default)
			)
			(layer "F.Fab")
		)
		(fp_line
			(start 0.12065 -0.2794)
			(end 0.12065 -0.3048)
			(stroke
				(width 0.1)
				(type default)
			)
			(layer "F.Fab")
		)
		(fp_line
			(start 0.12065 -0.3048)
			(end 0.67945 -0.3048)
			(stroke
				(width 0.1)
				(type default)
			)
			(layer "F.Fab")
		)
		(fp_line
			(start 0.120396 0.3048)
			(end 0.120396 0.2794)
			(stroke
				(width 0.1)
				(type default)
			)
			(layer "F.Fab")
		)
		(fp_line
			(start 0.120396 0.2794)
			(end -0.12065 0.2794)
			(stroke
				(width 0.1)
				(type default)
			)
			(layer "F.Fab")
		)
		(fp_line
			(start -0.12065 0.3048)
			(end -0.67945 0.3048)
			(stroke
				(width 0.1)
				(type default)
			)
			(layer "F.Fab")
		)
		(fp_line
			(start -0.12065 0.2794)
			(end -0.12065 0.3048)
			(stroke
				(width 0.1)
				(type default)
			)
			(layer "F.Fab")
		)
		(fp_line
			(start -0.12065 -0.2794)
			(end 0.12065 -0.2794)
			(stroke
				(width 0.1)
				(type default)
			)
			(layer "F.Fab")
		)
		(fp_line
			(start -0.12065 -0.305054)
			(end -0.12065 -0.2794)
			(stroke
				(width 0.1)
				(type default)
			)
			(layer "F.Fab")
		)
		(fp_line
			(start -0.67945 0.3048)
			(end -0.67945 -0.305054)
			(stroke
				(width 0.1)
				(type default)
			)
			(layer "F.Fab")
		)
		(fp_line
			(start -0.67945 -0.305054)
			(end -0.12065 -0.305054)
			(stroke
				(width 0.1)
				(type default)
			)
			(layer "F.Fab")
		)
		(pad "1" smd circle
			(at -0.40005 0 180)
			(size 0 0)
			(layers "F.Cu" "F.Mask" "F.Paste")
			(net "GPU_NVS_PWR_BRAKE_N_R")
		)
		(pad "2" smd circle
			(at 0.40005 0 180)
			(size 0 0)
			(layers "F.Cu" "F.Mask" "F.Paste")
			(net "GPU_NVS_PWR_BRAKE_N_BUF")
		)
	)
)
